(kicad_pcb
	(version 20260206)
	(generator "pcbnew")
	(generator_version "10.0")
	(general
		(thickness 1.6)
		(legacy_teardrops no)
	)
	(paper "A4")
	(title_block
		(title "baseboard — 13948-1b.1110WZS1818.brd")
		(comment 1 "Honey Badger (Wiwynn) / footprints 354-361 of 2523")
	)
	(layers
		(0 "F.Cu" signal "TOP")
		(4 "In1.Cu" signal "L2GND")
		(6 "In2.Cu" signal "L3")
		(8 "In3.Cu" signal "L4VCC")
		(10 "In4.Cu" signal "L5VCC")
		(12 "In5.Cu" signal "L6")
		(14 "In6.Cu" signal "L7GND")
		(2 "B.Cu" signal "BOTTOM")
		(9 "F.Adhes" user "F.Adhesive")
		(11 "B.Adhes" user "B.Adhesive")
		(13 "F.Paste" user "Package Geometry/Pastemask Top")
		(15 "B.Paste" user "Package Geometry/Pastemask Bottom")
		(5 "F.SilkS" user "Ref Des/Silkscreen Top")
		(7 "B.SilkS" user "Ref Des/Silkscreen Bottom")
		(1 "F.Mask" user "Board Geometry/Soldermask Top")
		(3 "B.Mask" user "Board Geometry/Soldermask Bottom")
		(17 "Dwgs.User" user "User.Drawings")
		(19 "Cmts.User" user "User.Comments")
		(21 "Eco1.User" user "User.Eco1")
		(23 "Eco2.User" user "User.Eco2")
		(25 "Edge.Cuts" user "Board Geometry/Outline")
		(27 "Margin" user)
		(31 "F.CrtYd" user "Package Geometry/Place Bound Top")
		(29 "B.CrtYd" user "Package Geometry/Place Bound Bottom")
		(35 "F.Fab" user "Ref Des/Assembly Top")
		(33 "B.Fab" user "Ref Des/Assembly Bottom")
	)
	(footprint ""
		(layer "F.Cu")
		(at 90.937842 -117.800882 90)
		(property "Reference" "SR743"
			(at 0 0 90)
			(layer "F.SilkS")
			(hide yes)
			(effects
				(font
					(size 1.27 1.27)
				)
			)
		)
		(property "Value" "2K2R2F-GP"
			(at 0.064008 -3.993896 90)
			(unlocked yes)
			(layer "F.Fab")
			(hide yes)
			(effects
				(font
					(size 1.016 1.016)
					(thickness 0.1524)
				)
			)
		)
		(property "Device Type" "R402H16"
			(at 0.064008 -5.517896 90)
			(unlocked yes)
			(layer "F.Fab")
			(hide yes)
			(effects
				(font
					(size 1.016 1.016)
					(thickness 0.1524)
				)
			)
		)
		(duplicate_pad_numbers_are_jumpers no)
		(fp_line
			(start 0.508 -0.9398)
			(end -0.508 -0.9398)
			(stroke
				(width 0.1524)
				(type default)
			)
			(layer "F.SilkS")
		)
		(fp_line
			(start -0.508 -0.9398)
			(end -0.508 0.9398)
			(stroke
				(width 0.1524)
				(type default)
			)
			(layer "F.SilkS")
		)
		(fp_rect
			(start -0.508 0.9398)
			(end 0.508 -0.9398)
			(stroke
				(width 0)
				(type default)
			)
			(fill no)
			(layer "F.CrtYd")
		)
		(fp_rect
			(start -0.508 0.9398)
			(end 0.508 -0.9398)
			(stroke
				(width 0)
				(type default)
			)
			(fill no)
			(layer "F.Fab")
		)
		(pad "1" smd custom
			(at 0 -0.4445 90)
			(size 0.1397 0.1397)
			(layers "F.Cu" "F.Mask" "F.Paste")
			(net "EXP_I2C_SDA_1")
			(options
				(clearance outline)
				(anchor circle)
			)
			(primitives
				(gr_poly
					(pts
						(arc
							(start -0.1778 -0.2794)
							(mid -0.249642 -0.249642)
							(end -0.2794 -0.1778)
						)
						(arc
							(start -0.2794 0.1778)
							(mid -0.249642 0.249642)
							(end -0.1778 0.2794)
						)
						(arc
							(start 0.1778 0.2794)
							(mid 0.249642 0.249642)
							(end 0.2794 0.1778)
						)
						(arc
							(start 0.2794 -0.1778)
							(mid 0.249642 -0.249642)
							(end 0.1778 -0.2794)
						)
					)
					(width 0)
					(fill yes)
				)
			)
		)
		(pad "2" smd custom
			(at 0 0.4445 90)
			(size 0.1397 0.1397)
			(layers "F.Cu" "F.Mask" "F.Paste")
			(net "P1V8_E")
			(options
				(clearance outline)
				(anchor circle)
			)
			(primitives
				(gr_poly
					(pts
						(arc
							(start -0.1778 -0.2794)
							(mid -0.249642 -0.249642)
							(end -0.2794 -0.1778)
						)
						(arc
							(start -0.2794 0.1778)
							(mid -0.249642 0.249642)
							(end -0.1778 0.2794)
						)
						(arc
							(start 0.1778 0.2794)
							(mid 0.249642 0.249642)
							(end 0.2794 0.1778)
						)
						(arc
							(start 0.2794 -0.1778)
							(mid 0.249642 -0.249642)
							(end 0.1778 -0.2794)
						)
					)
					(width 0)
					(fill yes)
				)
			)
		)
	)
	(footprint ""
		(layer "F.Cu")
		(at 249.555 -100.965)
		(property "Reference" "TP165"
			(at 0 0 0)
			(layer "F.SilkS")
			(hide yes)
			(effects
				(font
					(size 1.27 1.27)
				)
			)
		)
		(property "Value" "TPAD28"
			(at 0.0127 -1.8034 0)
			(unlocked yes)
			(layer "F.Fab")
			(hide yes)
			(effects
				(font
					(size 1.016 1.016)
					(thickness 0.1524)
				)
			)
		)
		(property "Device Type" "TPAD28"
			(at 0.0127 -3.3274 0)
			(unlocked yes)
			(layer "F.Fab")
			(hide yes)
			(effects
				(font
					(size 1.016 1.016)
					(thickness 0.1524)
				)
			)
		)
		(duplicate_pad_numbers_are_jumpers no)
		(fp_poly
			(pts
				(arc
					(start 0.3556 0)
					(mid -0.3556 0)
					(end 0.3556 0)
				)
			)
			(stroke
				(width 0)
				(type default)
			)
			(fill no)
			(layer "F.CrtYd")
		)
		(fp_poly
			(pts
				(arc
					(start 0.6096 0)
					(mid -0.6096 0)
					(end 0.6096 0)
				)
			)
			(stroke
				(width 0)
				(type default)
			)
			(fill no)
			(layer "F.Fab")
		)
		(pad "1" smd circle
			(at 0 0)
			(size 0.7112 0.7112)
			(layers "F.Cu" "F.Mask" "F.Paste")
			(net "BMC_JTAG_L_EN")
		)
	)
	(footprint ""
		(layer "F.Cu")
		(at 54.991 -180.086 180)
		(property "Reference" "SR811"
			(at 0 0 180)
			(layer "F.SilkS")
			(hide yes)
			(effects
				(font
					(size 1.27 1.27)
				)
			)
		)
		(property "Value" "4K75R2F-1-GP"
			(at 0.064008 -3.993896 180)
			(unlocked yes)
			(layer "F.Fab")
			(hide yes)
			(effects
				(font
					(size 1.016 1.016)
					(thickness 0.1524)
				)
			)
		)
		(property "Device Type" "R402H16"
			(at 0.064008 -5.517896 180)
			(unlocked yes)
			(layer "F.Fab")
			(hide yes)
			(effects
				(font
					(size 1.016 1.016)
					(thickness 0.1524)
				)
			)
		)
		(duplicate_pad_numbers_are_jumpers no)
		(fp_line
			(start 0.508 -0.9398)
			(end -0.508 -0.9398)
			(stroke
				(width 0.1524)
				(type default)
			)
			(layer "F.SilkS")
		)
		(fp_line
			(start -0.508 -0.9398)
			(end -0.508 0.9398)
			(stroke
				(width 0.1524)
				(type default)
			)
			(layer "F.SilkS")
		)
		(fp_rect
			(start -0.508 0.9398)
			(end 0.508 -0.9398)
			(stroke
				(width 0)
				(type default)
			)
			(fill no)
			(layer "F.CrtYd")
		)
		(fp_rect
			(start -0.508 0.9398)
			(end 0.508 -0.9398)
			(stroke
				(width 0)
				(type default)
			)
			(fill no)
			(layer "F.Fab")
		)
		(pad "1" smd custom
			(at 0 -0.4445 180)
			(size 0.1397 0.1397)
			(layers "F.Cu" "F.Mask" "F.Paste")
			(net "P1V8_E")
			(options
				(clearance outline)
				(anchor circle)
			)
			(primitives
				(gr_poly
					(pts
						(arc
							(start -0.1778 -0.2794)
							(mid -0.249642 -0.249642)
							(end -0.2794 -0.1778)
						)
						(arc
							(start -0.2794 0.1778)
							(mid -0.249642 0.249642)
							(end -0.1778 0.2794)
						)
						(arc
							(start 0.1778 0.2794)
							(mid 0.249642 0.249642)
							(end 0.2794 0.1778)
						)
						(arc
							(start 0.2794 -0.1778)
							(mid 0.249642 -0.249642)
							(end 0.1778 -0.2794)
						)
					)
					(width 0)
					(fill yes)
				)
			)
		)
		(pad "2" smd custom
			(at 0 0.4445 180)
			(size 0.1397 0.1397)
			(layers "F.Cu" "F.Mask" "F.Paste")
			(net "ICE_TMS")
			(options
				(clearance outline)
				(anchor circle)
			)
			(primitives
				(gr_poly
					(pts
						(arc
							(start -0.1778 -0.2794)
							(mid -0.249642 -0.249642)
							(end -0.2794 -0.1778)
						)
						(arc
							(start -0.2794 0.1778)
							(mid -0.249642 0.249642)
							(end -0.1778 0.2794)
						)
						(arc
							(start 0.1778 0.2794)
							(mid 0.249642 0.249642)
							(end 0.2794 0.1778)
						)
						(arc
							(start 0.2794 -0.1778)
							(mid 0.249642 -0.249642)
							(end 0.1778 -0.2794)
						)
					)
					(width 0)
					(fill yes)
				)
			)
		)
	)
	(footprint ""
		(layer "F.Cu")
		(at 80.51927 -81.191608 -90)
		(property "Reference" "SL21"
			(at 0 0 270)
			(layer "F.SilkS")
			(hide yes)
			(effects
				(font
					(size 1.27 1.27)
				)
			)
		)
		(property "Value" "MPZ2012S601AT-GP"
			(at 0 -4.2418 270)
			(unlocked yes)
			(layer "F.Fab")
			(hide yes)
			(effects
				(font
					(size 1.016 1.016)
					(thickness 0.1524)
				)
			)
		)
		(property "Device Type" "L805H42"
			(at 0 -5.7912 270)
			(unlocked yes)
			(layer "F.Fab")
			(hide yes)
			(effects
				(font
					(size 1.016 1.016)
					(thickness 0.1524)
				)
			)
		)
		(duplicate_pad_numbers_are_jumpers no)
		(fp_line
			(start -0.889 1.7018)
			(end -0.889 -1.7018)
			(stroke
				(width 0.1524)
				(type default)
			)
			(layer "F.SilkS")
		)
		(fp_line
			(start 0.889 1.7018)
			(end -0.889 1.7018)
			(stroke
				(width 0.1524)
				(type default)
			)
			(layer "F.SilkS")
		)
		(fp_line
			(start -0.889 -1.7018)
			(end 0.889 -1.7018)
			(stroke
				(width 0.1524)
				(type default)
			)
			(layer "F.SilkS")
		)
		(fp_line
			(start 0.889 -1.7018)
			(end 0.889 1.7018)
			(stroke
				(width 0.1524)
				(type default)
			)
			(layer "F.SilkS")
		)
		(fp_rect
			(start -0.9652 1.778)
			(end 0.9652 -1.778)
			(stroke
				(width 0)
				(type default)
			)
			(fill no)
			(layer "F.CrtYd")
		)
		(fp_rect
			(start -0.9652 1.778)
			(end 0.9652 -1.778)
			(stroke
				(width 0)
				(type default)
			)
			(fill no)
			(layer "F.Fab")
		)
		(pad "1" smd rect
			(at 0 -0.9652 270)
			(size 1.397 1.143)
			(layers "F.Cu" "F.Mask" "F.Paste")
			(net "XTAL_VDDA09")
		)
		(pad "2" smd rect
			(at 0 0.9652 270)
			(size 1.397 1.143)
			(layers "F.Cu" "F.Mask" "F.Paste")
			(net "P0V9_E")
		)
	)
	(footprint ""
		(layer "F.Cu")
		(at 262.001 -34.798 -90)
		(property "Reference" "PC51"
			(at 0 0 270)
			(layer "F.SilkS")
			(hide yes)
			(effects
				(font
					(size 1.27 1.27)
				)
			)
		)
		(property "Value" "SC1KP50V2KX-1GP"
			(at 1.1811 -2.7051 270)
			(unlocked yes)
			(layer "F.Fab")
			(hide yes)
			(effects
				(font
					(size 1.016 1.016)
					(thickness 0.1524)
				)
			)
		)
		(property "Device Type" "C402H22"
			(at 1.1811 -4.2291 270)
			(unlocked yes)
			(layer "F.Fab")
			(hide yes)
			(effects
				(font
					(size 1.016 1.016)
					(thickness 0.1524)
				)
			)
		)
		(duplicate_pad_numbers_are_jumpers no)
		(fp_rect
			(start -0.4318 0.9525)
			(end 0.4318 -0.9525)
			(stroke
				(width 0)
				(type default)
			)
			(fill no)
			(layer "F.CrtYd")
		)
		(fp_rect
			(start -0.4318 0.9525)
			(end 0.4318 -0.9525)
			(stroke
				(width 0)
				(type default)
			)
			(fill no)
			(layer "F.Fab")
		)
		(pad "1" smd custom
			(at 0 -0.4445 270)
			(size 0.1524 0.1524)
			(layers "F.Cu" "F.Mask" "F.Paste")
			(net "P1V8_STBY_LL_R")
			(options
				(clearance outline)
				(anchor circle)
			)
			(primitives
				(gr_poly
					(pts
						(arc
							(start 0.3048 -0.2032)
							(mid 0.275042 -0.275042)
							(end 0.2032 -0.3048)
						)
						(arc
							(start -0.2032 -0.3048)
							(mid -0.275042 -0.275042)
							(end -0.3048 -0.2032)
						)
						(arc
							(start -0.3048 0.2032)
							(mid -0.275042 0.275042)
							(end -0.2032 0.3048)
						)
						(arc
							(start 0.2032 0.3048)
							(mid 0.275042 0.275042)
							(end 0.3048 0.2032)
						)
					)
					(width 0)
					(fill yes)
				)
			)
		)
		(pad "2" smd custom
			(at 0 0.4445 270)
			(size 0.1524 0.1524)
			(layers "F.Cu" "F.Mask" "F.Paste")
			(net "P1V8_STBY_VFB")
			(options
				(clearance outline)
				(anchor circle)
			)
			(primitives
				(gr_poly
					(pts
						(arc
							(start 0.3048 -0.2032)
							(mid 0.275042 -0.275042)
							(end 0.2032 -0.3048)
						)
						(arc
							(start -0.2032 -0.3048)
							(mid -0.275042 -0.275042)
							(end -0.3048 -0.2032)
						)
						(arc
							(start -0.3048 0.2032)
							(mid -0.275042 0.275042)
							(end -0.2032 0.3048)
						)
						(arc
							(start 0.2032 0.3048)
							(mid 0.275042 0.275042)
							(end 0.3048 0.2032)
						)
					)
					(width 0)
					(fill yes)
				)
			)
		)
	)
	(footprint ""
		(layer "F.Cu")
		(at 23.056088 -195.708016 90)
		(property "Reference" "SR309"
			(at 0 0 90)
			(layer "F.SilkS")
			(hide yes)
			(effects
				(font
					(size 1.27 1.27)
				)
			)
		)
		(property "Value" "0R2J-2-GP"
			(at 0.064008 -3.993896 90)
			(unlocked yes)
			(layer "F.Fab")
			(hide yes)
			(effects
				(font
					(size 1.016 1.016)
					(thickness 0.1524)
				)
			)
		)
		(property "Device Type" "R402H16"
			(at 0.064008 -5.517896 90)
			(unlocked yes)
			(layer "F.Fab")
			(hide yes)
			(effects
				(font
					(size 1.016 1.016)
					(thickness 0.1524)
				)
			)
		)
		(duplicate_pad_numbers_are_jumpers no)
		(fp_line
			(start 0.508 -0.9398)
			(end -0.508 -0.9398)
			(stroke
				(width 0.1524)
				(type default)
			)
			(layer "F.SilkS")
		)
		(fp_line
			(start -0.508 -0.9398)
			(end -0.508 0.9398)
			(stroke
				(width 0.1524)
				(type default)
			)
			(layer "F.SilkS")
		)
		(fp_rect
			(start -0.508 0.9398)
			(end 0.508 -0.9398)
			(stroke
				(width 0)
				(type default)
			)
			(fill no)
			(layer "F.CrtYd")
		)
		(fp_rect
			(start -0.508 0.9398)
			(end 0.508 -0.9398)
			(stroke
				(width 0)
				(type default)
			)
			(fill no)
			(layer "F.Fab")
		)
		(pad "1" smd custom
			(at 0 -0.4445 90)
			(size 0.1397 0.1397)
			(layers "F.Cu" "F.Mask" "F.Paste")
			(net "I2C_IO_EXP_RESET#")
			(options
				(clearance outline)
				(anchor circle)
			)
			(primitives
				(gr_poly
					(pts
						(arc
							(start -0.1778 -0.2794)
							(mid -0.249642 -0.249642)
							(end -0.2794 -0.1778)
						)
						(arc
							(start -0.2794 0.1778)
							(mid -0.249642 0.249642)
							(end -0.1778 0.2794)
						)
						(arc
							(start 0.1778 0.2794)
							(mid 0.249642 0.249642)
							(end 0.2794 0.1778)
						)
						(arc
							(start 0.2794 -0.1778)
							(mid 0.249642 -0.249642)
							(end 0.1778 -0.2794)
						)
					)
					(width 0)
					(fill yes)
				)
			)
		)
		(pad "2" smd custom
			(at 0 0.4445 90)
			(size 0.1397 0.1397)
			(layers "F.Cu" "F.Mask" "F.Paste")
			(net "I2C_IO_EXP_RESET#_PRST")
			(options
				(clearance outline)
				(anchor circle)
			)
			(primitives
				(gr_poly
					(pts
						(arc
							(start -0.1778 -0.2794)
							(mid -0.249642 -0.249642)
							(end -0.2794 -0.1778)
						)
						(arc
							(start -0.2794 0.1778)
							(mid -0.249642 0.249642)
							(end -0.1778 0.2794)
						)
						(arc
							(start 0.1778 0.2794)
							(mid 0.249642 0.249642)
							(end 0.2794 0.1778)
						)
						(arc
							(start 0.2794 -0.1778)
							(mid 0.249642 -0.249642)
							(end 0.1778 -0.2794)
						)
					)
					(width 0)
					(fill yes)
				)
			)
		)
	)
	(footprint ""
		(layer "F.Cu")
		(at 177.927 -219.329 -90)
		(property "Reference" "R1579"
			(at 0 0 270)
			(layer "F.SilkS")
			(hide yes)
			(effects
				(font
					(size 1.27 1.27)
				)
			)
		)
		(property "Value" "4K7R2F-GP"
			(at 0.064008 -3.993896 270)
			(unlocked yes)
			(layer "F.Fab")
			(hide yes)
			(effects
				(font
					(size 1.016 1.016)
					(thickness 0.1524)
				)
			)
		)
		(property "Device Type" "R402H16"
			(at 0.064008 -5.517896 270)
			(unlocked yes)
			(layer "F.Fab")
			(hide yes)
			(effects
				(font
					(size 1.016 1.016)
					(thickness 0.1524)
				)
			)
		)
		(duplicate_pad_numbers_are_jumpers no)
		(fp_line
			(start -0.508 -0.9398)
			(end -0.508 0.9398)
			(stroke
				(width 0.1524)
				(type default)
			)
			(layer "F.SilkS")
		)
		(fp_line
			(start 0.508 -0.9398)
			(end -0.508 -0.9398)
			(stroke
				(width 0.1524)
				(type default)
			)
			(layer "F.SilkS")
		)
		(fp_rect
			(start -0.508 0.9398)
			(end 0.508 -0.9398)
			(stroke
				(width 0)
				(type default)
			)
			(fill no)
			(layer "F.CrtYd")
		)
		(fp_rect
			(start -0.508 0.9398)
			(end 0.508 -0.9398)
			(stroke
				(width 0)
				(type default)
			)
			(fill no)
			(layer "F.Fab")
		)
		(pad "1" smd custom
			(at 0 -0.4445 270)
			(size 0.1397 0.1397)
			(layers "F.Cu" "F.Mask" "F.Paste")
			(net "P3V3_STBY")
			(options
				(clearance outline)
				(anchor circle)
			)
			(primitives
				(gr_poly
					(pts
						(arc
							(start -0.1778 -0.2794)
							(mid -0.249642 -0.249642)
							(end -0.2794 -0.1778)
						)
						(arc
							(start -0.2794 0.1778)
							(mid -0.249642 0.249642)
							(end -0.1778 0.2794)
						)
						(arc
							(start 0.1778 0.2794)
							(mid 0.249642 0.249642)
							(end 0.2794 0.1778)
						)
						(arc
							(start 0.2794 -0.1778)
							(mid 0.249642 -0.249642)
							(end 0.1778 -0.2794)
						)
					)
					(width 0)
					(fill yes)
				)
			)
		)
		(pad "2" smd custom
			(at 0 0.4445 270)
			(size 0.1397 0.1397)
			(layers "F.Cu" "F.Mask" "F.Paste")
			(net "PMU_PWRBTN_N")
			(options
				(clearance outline)
				(anchor circle)
			)
			(primitives
				(gr_poly
					(pts
						(arc
							(start -0.1778 -0.2794)
							(mid -0.249642 -0.249642)
							(end -0.2794 -0.1778)
						)
						(arc
							(start -0.2794 0.1778)
							(mid -0.249642 0.249642)
							(end -0.1778 0.2794)
						)
						(arc
							(start 0.1778 0.2794)
							(mid 0.249642 0.249642)
							(end 0.2794 0.1778)
						)
						(arc
							(start 0.2794 -0.1778)
							(mid 0.249642 -0.249642)
							(end 0.1778 -0.2794)
						)
					)
					(width 0)
					(fill yes)
				)
			)
		)
	)
	(footprint ""
		(layer "F.Cu")
		(at 133.25729 -53.895752)
		(property "Reference" "STP117"
			(at 0 0 0)
			(layer "F.SilkS")
			(hide yes)
			(effects
				(font
					(size 1.27 1.27)
				)
			)
		)
		(property "Value" "TPAD28"
			(at 0.0127 -1.8034 0)
			(unlocked yes)
			(layer "F.Fab")
			(hide yes)
			(effects
				(font
					(size 1.016 1.016)
					(thickness 0.1524)
				)
			)
		)
		(property "Device Type" "TPAD28"
			(at 0.0127 -3.3274 0)
			(unlocked yes)
			(layer "F.Fab")
			(hide yes)
			(effects
				(font
					(size 1.016 1.016)
					(thickness 0.1524)
				)
			)
		)
		(duplicate_pad_numbers_are_jumpers no)
		(fp_poly
			(pts
				(arc
					(start 0.3556 0)
					(mid -0.3556 0)
					(end 0.3556 0)
				)
			)
			(stroke
				(width 0)
				(type default)
			)
			(fill no)
			(layer "F.CrtYd")
		)
		(fp_poly
			(pts
				(arc
					(start 0.6096 0)
					(mid -0.6096 0)
					(end 0.6096 0)
				)
			)
			(stroke
				(width 0)
				(type default)
			)
			(fill no)
			(layer "F.Fab")
		)
		(pad "1" smd circle
			(at 0 0)
			(size 0.7112 0.7112)
			(layers "F.Cu" "F.Mask" "F.Paste")
			(net "XM_ADDR_17")
		)
	)
)
